(kicad_pcb
	(version 20260206)
	(generator "pcbnew")
	(generator_version "10.0")
	(general
		(thickness 1.6)
		(legacy_teardrops no)
	)
	(paper "A4")
	(title_block
		(title "03242023_DA0F0TMBIJ0_F0T_Motherboard_J_brd_V01_OCP.brd")
		(comment 1 "Grand Teton / footprints 5066-5072 of 6105")
	)
	(layers
		(0 "F.Cu" signal "TOP")
		(4 "In1.Cu" signal "GND")
		(6 "In2.Cu" signal "IN1")
		(8 "In3.Cu" signal "GND1")
		(10 "In4.Cu" signal "IN2")
		(12 "In5.Cu" signal "GND2")
		(14 "In6.Cu" signal "IN3")
		(16 "In7.Cu" signal "GND3")
		(18 "In8.Cu" signal "VCC")
		(20 "In9.Cu" signal "VCC1")
		(22 "In10.Cu" signal "GND4")
		(24 "In11.Cu" signal "IN4")
		(26 "In12.Cu" signal "GND5")
		(28 "In13.Cu" signal "IN5")
		(30 "In14.Cu" signal "GND6")
		(32 "In15.Cu" signal "IN6")
		(34 "In16.Cu" signal "GND7")
		(2 "B.Cu" signal "BOTTOM")
		(9 "F.Adhes" user "F.Adhesive")
		(11 "B.Adhes" user "B.Adhesive")
		(13 "F.Paste" user "Package Geometry/Pastemask Top")
		(15 "B.Paste" user "Package Geometry/Pastemask Bottom")
		(5 "F.SilkS" user "Ref Des/Silkscreen Top")
		(7 "B.SilkS" user "Ref Des/Silkscreen Bottom")
		(1 "F.Mask" user "Board Geometry/Soldermask Top")
		(3 "B.Mask" user "Board Geometry/Soldermask Bottom")
		(17 "Dwgs.User" user "User.Drawings")
		(19 "Cmts.User" user "User.Comments")
		(21 "Eco1.User" user "User.Eco1")
		(23 "Eco2.User" user "User.Eco2")
		(25 "Edge.Cuts" user "Board Geometry/Outline")
		(27 "Margin" user)
		(31 "F.CrtYd" user "Package Geometry/Place Bound Top")
		(29 "B.CrtYd" user "Package Geometry/Place Bound Bottom")
		(35 "F.Fab" user "Ref Des/Assembly Top")
		(33 "B.Fab" user "Ref Des/Assembly Bottom")
	)
	(footprint ""
		(layer "B.Cu")
		(at 420.682166 -135.146034 180)
		(property "Reference" "PR108"
			(at 0 0 0)
			(layer "B.SilkS")
			(hide yes)
			(effects
				(font
					(size 1.27 1.27)
				)
				(justify mirror)
			)
		)
		(property "Value" ""
			(at 0 0 0)
			(layer "B.Fab")
			(effects
				(font
					(size 1.27 1.27)
				)
				(justify mirror)
			)
		)
		(duplicate_pad_numbers_are_jumpers no)
		(fp_line
			(start 0.7874 0.4064)
			(end 0.7874 -0.4064)
			(stroke
				(width 0.1524)
				(type default)
			)
			(layer "B.SilkS")
		)
		(fp_line
			(start 0.7874 -0.4064)
			(end -0.7874 -0.4064)
			(stroke
				(width 0.1524)
				(type default)
			)
			(layer "B.SilkS")
		)
		(fp_line
			(start -0.7874 0.4064)
			(end 0.7874 0.4064)
			(stroke
				(width 0.1524)
				(type default)
			)
			(layer "B.SilkS")
		)
		(fp_line
			(start -0.7874 -0.4064)
			(end -0.7874 0.4064)
			(stroke
				(width 0.1524)
				(type default)
			)
			(layer "B.SilkS")
		)
		(fp_line
			(start 0.67945 0.3048)
			(end 0.67945 -0.305054)
			(stroke
				(width 0.1)
				(type default)
			)
			(layer "B.Fab")
		)
		(fp_line
			(start 0.67945 -0.305054)
			(end 0.12065 -0.305054)
			(stroke
				(width 0.1)
				(type default)
			)
			(layer "B.Fab")
		)
		(fp_line
			(start 0.12065 0.3048)
			(end 0.67945 0.3048)
			(stroke
				(width 0.1)
				(type default)
			)
			(layer "B.Fab")
		)
		(fp_line
			(start 0.12065 0.2794)
			(end 0.12065 0.3048)
			(stroke
				(width 0.1)
				(type default)
			)
			(layer "B.Fab")
		)
		(fp_line
			(start 0.12065 -0.2794)
			(end -0.12065 -0.2794)
			(stroke
				(width 0.1)
				(type default)
			)
			(layer "B.Fab")
		)
		(fp_line
			(start 0.12065 -0.305054)
			(end 0.12065 -0.2794)
			(stroke
				(width 0.1)
				(type default)
			)
			(layer "B.Fab")
		)
		(fp_line
			(start -0.120396 0.3048)
			(end -0.120396 0.2794)
			(stroke
				(width 0.1)
				(type default)
			)
			(layer "B.Fab")
		)
		(fp_line
			(start -0.120396 0.2794)
			(end 0.12065 0.2794)
			(stroke
				(width 0.1)
				(type default)
			)
			(layer "B.Fab")
		)
		(fp_line
			(start -0.12065 -0.2794)
			(end -0.12065 -0.3048)
			(stroke
				(width 0.1)
				(type default)
			)
			(layer "B.Fab")
		)
		(fp_line
			(start -0.12065 -0.3048)
			(end -0.67945 -0.3048)
			(stroke
				(width 0.1)
				(type default)
			)
			(layer "B.Fab")
		)
		(fp_line
			(start -0.67945 0.3048)
			(end -0.120396 0.3048)
			(stroke
				(width 0.1)
				(type default)
			)
			(layer "B.Fab")
		)
		(fp_line
			(start -0.67945 -0.3048)
			(end -0.67945 0.3048)
			(stroke
				(width 0.1)
				(type default)
			)
			(layer "B.Fab")
		)
		(pad "1" smd circle
			(at 0.40005 0)
			(size 0 0)
			(layers "B.Cu" "B.Mask" "B.Paste")
			(net "P12V_AUX")
		)
		(pad "2" smd circle
			(at -0.40005 0)
			(size 0 0)
			(layers "B.Cu" "B.Mask" "B.Paste")
			(net "PVCCINFAON_CPU0_VIN_CSNIN")
		)
	)
	(footprint ""
		(layer "B.Cu")
		(at 369.756436 -354.93833 -90)
		(property "Reference" "R2406"
			(at 0 0 90)
			(layer "B.SilkS")
			(hide yes)
			(effects
				(font
					(size 1.27 1.27)
				)
				(justify mirror)
			)
		)
		(property "Value" ""
			(at 0 0 90)
			(layer "B.Fab")
			(effects
				(font
					(size 1.27 1.27)
				)
				(justify mirror)
			)
		)
		(duplicate_pad_numbers_are_jumpers no)
		(fp_line
			(start -0.7874 0.4064)
			(end 0.7874 0.4064)
			(stroke
				(width 0.1524)
				(type default)
			)
			(layer "B.SilkS")
		)
		(fp_line
			(start 0.7874 0.4064)
			(end 0.7874 -0.4064)
			(stroke
				(width 0.1524)
				(type default)
			)
			(layer "B.SilkS")
		)
		(fp_line
			(start -0.7874 -0.4064)
			(end -0.7874 0.4064)
			(stroke
				(width 0.1524)
				(type default)
			)
			(layer "B.SilkS")
		)
		(fp_line
			(start 0.7874 -0.4064)
			(end -0.7874 -0.4064)
			(stroke
				(width 0.1524)
				(type default)
			)
			(layer "B.SilkS")
		)
		(fp_line
			(start -0.67945 0.3048)
			(end -0.120396 0.3048)
			(stroke
				(width 0.1)
				(type default)
			)
			(layer "B.Fab")
		)
		(fp_line
			(start -0.120396 0.3048)
			(end -0.120396 0.2794)
			(stroke
				(width 0.1)
				(type default)
			)
			(layer "B.Fab")
		)
		(fp_line
			(start 0.12065 0.3048)
			(end 0.67945 0.3048)
			(stroke
				(width 0.1)
				(type default)
			)
			(layer "B.Fab")
		)
		(fp_line
			(start 0.67945 0.3048)
			(end 0.67945 -0.305054)
			(stroke
				(width 0.1)
				(type default)
			)
			(layer "B.Fab")
		)
		(fp_line
			(start -0.120396 0.2794)
			(end 0.12065 0.2794)
			(stroke
				(width 0.1)
				(type default)
			)
			(layer "B.Fab")
		)
		(fp_line
			(start 0.12065 0.2794)
			(end 0.12065 0.3048)
			(stroke
				(width 0.1)
				(type default)
			)
			(layer "B.Fab")
		)
		(fp_line
			(start -0.12065 -0.2794)
			(end -0.12065 -0.3048)
			(stroke
				(width 0.1)
				(type default)
			)
			(layer "B.Fab")
		)
		(fp_line
			(start 0.12065 -0.2794)
			(end -0.12065 -0.2794)
			(stroke
				(width 0.1)
				(type default)
			)
			(layer "B.Fab")
		)
		(fp_line
			(start -0.67945 -0.3048)
			(end -0.67945 0.3048)
			(stroke
				(width 0.1)
				(type default)
			)
			(layer "B.Fab")
		)
		(fp_line
			(start -0.12065 -0.3048)
			(end -0.67945 -0.3048)
			(stroke
				(width 0.1)
				(type default)
			)
			(layer "B.Fab")
		)
		(fp_line
			(start 0.12065 -0.305054)
			(end 0.12065 -0.2794)
			(stroke
				(width 0.1)
				(type default)
			)
			(layer "B.Fab")
		)
		(fp_line
			(start 0.67945 -0.305054)
			(end 0.12065 -0.305054)
			(stroke
				(width 0.1)
				(type default)
			)
			(layer "B.Fab")
		)
		(pad "1" smd circle
			(at 0.40005 0 90)
			(size 0 0)
			(layers "B.Cu" "B.Mask" "B.Paste")
			(net "P3V3_AUX")
		)
		(pad "2" smd circle
			(at -0.40005 0 90)
			(size 0 0)
			(layers "B.Cu" "B.Mask" "B.Paste")
			(net "FM_PVPP_HBM_CPU0_EN")
		)
	)
	(footprint ""
		(layer "B.Cu")
		(at 168.83888 -102.707948)
		(property "Reference" "C1938"
			(at 0 0 0)
			(layer "B.SilkS")
			(hide yes)
			(effects
				(font
					(size 1.27 1.27)
				)
				(justify mirror)
			)
		)
		(property "Value" ""
			(at 0 0 0)
			(layer "B.Fab")
			(effects
				(font
					(size 1.27 1.27)
				)
				(justify mirror)
			)
		)
		(duplicate_pad_numbers_are_jumpers no)
		(fp_line
			(start -0.7874 -0.4064)
			(end -0.7874 0.4064)
			(stroke
				(width 0.1524)
				(type default)
			)
			(layer "B.SilkS")
		)
		(fp_line
			(start -0.7874 0.4064)
			(end 0.7874 0.4064)
			(stroke
				(width 0.1524)
				(type default)
			)
			(layer "B.SilkS")
		)
		(fp_line
			(start 0.7874 -0.4064)
			(end -0.7874 -0.4064)
			(stroke
				(width 0.1524)
				(type default)
			)
			(layer "B.SilkS")
		)
		(fp_line
			(start 0.7874 0.4064)
			(end 0.7874 -0.4064)
			(stroke
				(width 0.1524)
				(type default)
			)
			(layer "B.SilkS")
		)
		(fp_line
			(start -0.67945 -0.3048)
			(end -0.67945 0.3048)
			(stroke
				(width 0.1)
				(type default)
			)
			(layer "B.Fab")
		)
		(fp_line
			(start -0.67945 0.3048)
			(end -0.120396 0.3048)
			(stroke
				(width 0.1)
				(type default)
			)
			(layer "B.Fab")
		)
		(fp_line
			(start -0.12065 -0.3048)
			(end -0.67945 -0.3048)
			(stroke
				(width 0.1)
				(type default)
			)
			(layer "B.Fab")
		)
		(fp_line
			(start -0.12065 -0.2794)
			(end -0.12065 -0.3048)
			(stroke
				(width 0.1)
				(type default)
			)
			(layer "B.Fab")
		)
		(fp_line
			(start -0.120396 0.2794)
			(end 0.12065 0.2794)
			(stroke
				(width 0.1)
				(type default)
			)
			(layer "B.Fab")
		)
		(fp_line
			(start -0.120396 0.3048)
			(end -0.120396 0.2794)
			(stroke
				(width 0.1)
				(type default)
			)
			(layer "B.Fab")
		)
		(fp_line
			(start 0.12065 -0.305054)
			(end 0.12065 -0.2794)
			(stroke
				(width 0.1)
				(type default)
			)
			(layer "B.Fab")
		)
		(fp_line
			(start 0.12065 -0.2794)
			(end -0.12065 -0.2794)
			(stroke
				(width 0.1)
				(type default)
			)
			(layer "B.Fab")
		)
		(fp_line
			(start 0.12065 0.2794)
			(end 0.12065 0.3048)
			(stroke
				(width 0.1)
				(type default)
			)
			(layer "B.Fab")
		)
		(fp_line
			(start 0.12065 0.3048)
			(end 0.67945 0.3048)
			(stroke
				(width 0.1)
				(type default)
			)
			(layer "B.Fab")
		)
		(fp_line
			(start 0.67945 -0.305054)
			(end 0.12065 -0.305054)
			(stroke
				(width 0.1)
				(type default)
			)
			(layer "B.Fab")
		)
		(fp_line
			(start 0.67945 0.3048)
			(end 0.67945 -0.305054)
			(stroke
				(width 0.1)
				(type default)
			)
			(layer "B.Fab")
		)
		(pad "1" smd circle
			(at 0.40005 0 180)
			(size 0 0)
			(layers "B.Cu" "B.Mask" "B.Paste")
			(net "P3V3_AUX_FPGA_VCCIO0")
		)
		(pad "2" smd circle
			(at -0.40005 0 180)
			(size 0 0)
			(layers "B.Cu" "B.Mask" "B.Paste")
			(net "GND")
		)
	)
	(footprint ""
		(layer "B.Cu")
		(at 342.453214 -52.202334 -90)
		(property "Reference" "C1257"
			(at 0 0 90)
			(layer "B.SilkS")
			(hide yes)
			(effects
				(font
					(size 1.27 1.27)
				)
				(justify mirror)
			)
		)
		(property "Value" ""
			(at 0 0 90)
			(layer "B.Fab")
			(effects
				(font
					(size 1.27 1.27)
				)
				(justify mirror)
			)
		)
		(duplicate_pad_numbers_are_jumpers no)
		(fp_line
			(start -0.7874 0.4064)
			(end 0.7874 0.4064)
			(stroke
				(width 0.1524)
				(type default)
			)
			(layer "B.SilkS")
		)
		(fp_line
			(start 0.7874 0.4064)
			(end 0.7874 -0.4064)
			(stroke
				(width 0.1524)
				(type default)
			)
			(layer "B.SilkS")
		)
		(fp_line
			(start -0.7874 -0.4064)
			(end -0.7874 0.4064)
			(stroke
				(width 0.1524)
				(type default)
			)
			(layer "B.SilkS")
		)
		(fp_line
			(start 0.7874 -0.4064)
			(end -0.7874 -0.4064)
			(stroke
				(width 0.1524)
				(type default)
			)
			(layer "B.SilkS")
		)
		(fp_line
			(start -0.67945 0.3048)
			(end -0.120396 0.3048)
			(stroke
				(width 0.1)
				(type default)
			)
			(layer "B.Fab")
		)
		(fp_line
			(start -0.120396 0.3048)
			(end -0.120396 0.2794)
			(stroke
				(width 0.1)
				(type default)
			)
			(layer "B.Fab")
		)
		(fp_line
			(start 0.12065 0.3048)
			(end 0.67945 0.3048)
			(stroke
				(width 0.1)
				(type default)
			)
			(layer "B.Fab")
		)
		(fp_line
			(start 0.67945 0.3048)
			(end 0.67945 -0.305054)
			(stroke
				(width 0.1)
				(type default)
			)
			(layer "B.Fab")
		)
		(fp_line
			(start -0.120396 0.2794)
			(end 0.12065 0.2794)
			(stroke
				(width 0.1)
				(type default)
			)
			(layer "B.Fab")
		)
		(fp_line
			(start 0.12065 0.2794)
			(end 0.12065 0.3048)
			(stroke
				(width 0.1)
				(type default)
			)
			(layer "B.Fab")
		)
		(fp_line
			(start -0.12065 -0.2794)
			(end -0.12065 -0.3048)
			(stroke
				(width 0.1)
				(type default)
			)
			(layer "B.Fab")
		)
		(fp_line
			(start 0.12065 -0.2794)
			(end -0.12065 -0.2794)
			(stroke
				(width 0.1)
				(type default)
			)
			(layer "B.Fab")
		)
		(fp_line
			(start -0.67945 -0.3048)
			(end -0.67945 0.3048)
			(stroke
				(width 0.1)
				(type default)
			)
			(layer "B.Fab")
		)
		(fp_line
			(start -0.12065 -0.3048)
			(end -0.67945 -0.3048)
			(stroke
				(width 0.1)
				(type default)
			)
			(layer "B.Fab")
		)
		(fp_line
			(start 0.12065 -0.305054)
			(end 0.12065 -0.2794)
			(stroke
				(width 0.1)
				(type default)
			)
			(layer "B.Fab")
		)
		(fp_line
			(start 0.67945 -0.305054)
			(end 0.12065 -0.305054)
			(stroke
				(width 0.1)
				(type default)
			)
			(layer "B.Fab")
		)
		(pad "1" smd circle
			(at 0.40005 0 90)
			(size 0 0)
			(layers "B.Cu" "B.Mask" "B.Paste")
			(net "P1V8_PCH_PLL_AUX")
		)
		(pad "2" smd circle
			(at -0.40005 0 90)
			(size 0 0)
			(layers "B.Cu" "B.Mask" "B.Paste")
			(net "GND")
		)
	)
	(footprint ""
		(layer "B.Cu")
		(at 204.088746 -321.554856 -90)
		(property "Reference" "C74"
			(at 0 0 90)
			(layer "B.SilkS")
			(hide yes)
			(effects
				(font
					(size 1.27 1.27)
				)
				(justify mirror)
			)
		)
		(property "Value" ""
			(at 0 0 90)
			(layer "B.Fab")
			(effects
				(font
					(size 1.27 1.27)
				)
				(justify mirror)
			)
		)
		(duplicate_pad_numbers_are_jumpers no)
		(fp_line
			(start -1.524 0.762)
			(end 1.524 0.762)
			(stroke
				(width 0.1524)
				(type default)
			)
			(layer "B.SilkS")
		)
		(fp_line
			(start 1.524 0.762)
			(end 1.524 -0.762)
			(stroke
				(width 0.1524)
				(type default)
			)
			(layer "B.SilkS")
		)
		(fp_line
			(start -1.524 -0.762)
			(end -1.524 0.762)
			(stroke
				(width 0.1524)
				(type default)
			)
			(layer "B.SilkS")
		)
		(fp_line
			(start 1.524 -0.762)
			(end -1.524 -0.762)
			(stroke
				(width 0.1524)
				(type default)
			)
			(layer "B.SilkS")
		)
		(fp_line
			(start -1.1049 0.724916)
			(end -1.1049 -0.724916)
			(stroke
				(width 0.1)
				(type default)
			)
			(layer "B.Fab")
		)
		(fp_line
			(start 1.1049 0.724916)
			(end -1.1049 0.724916)
			(stroke
				(width 0.1)
				(type default)
			)
			(layer "B.Fab")
		)
		(fp_line
			(start -1.1049 -0.724916)
			(end 1.1049 -0.724916)
			(stroke
				(width 0.1)
				(type default)
			)
			(layer "B.Fab")
		)
		(fp_line
			(start 1.1049 -0.724916)
			(end 1.1049 0.724916)
			(stroke
				(width 0.1)
				(type default)
			)
			(layer "B.Fab")
		)
		(pad "1" smd rect
			(at 0.889 0 270)
			(size 1.016 1.27)
			(layers "B.Cu" "B.Mask" "B.Paste")
			(net "P12V_S3_AUX_CPU1_NVDIMM")
		)
		(pad "2" smd rect
			(at -0.889 0 270)
			(size 1.016 1.27)
			(layers "B.Cu" "B.Mask" "B.Paste")
			(net "GND")
		)
	)
	(footprint ""
		(layer "B.Cu")
		(at 433.61864 -52.2478 -90)
		(property "Reference" "R1655"
			(at 0 0 90)
			(layer "B.SilkS")
			(hide yes)
			(effects
				(font
					(size 1.27 1.27)
				)
				(justify mirror)
			)
		)
		(property "Value" ""
			(at 0 0 90)
			(layer "B.Fab")
			(effects
				(font
					(size 1.27 1.27)
				)
				(justify mirror)
			)
		)
		(duplicate_pad_numbers_are_jumpers no)
		(fp_line
			(start -0.7874 0.4064)
			(end 0.7874 0.4064)
			(stroke
				(width 0.1524)
				(type default)
			)
			(layer "B.SilkS")
		)
		(fp_line
			(start 0.7874 0.4064)
			(end 0.7874 -0.4064)
			(stroke
				(width 0.1524)
				(type default)
			)
			(layer "B.SilkS")
		)
		(fp_line
			(start -0.7874 -0.4064)
			(end -0.7874 0.4064)
			(stroke
				(width 0.1524)
				(type default)
			)
			(layer "B.SilkS")
		)
		(fp_line
			(start 0.7874 -0.4064)
			(end -0.7874 -0.4064)
			(stroke
				(width 0.1524)
				(type default)
			)
			(layer "B.SilkS")
		)
		(fp_line
			(start -0.67945 0.3048)
			(end -0.120396 0.3048)
			(stroke
				(width 0.1)
				(type default)
			)
			(layer "B.Fab")
		)
		(fp_line
			(start -0.120396 0.3048)
			(end -0.120396 0.2794)
			(stroke
				(width 0.1)
				(type default)
			)
			(layer "B.Fab")
		)
		(fp_line
			(start 0.12065 0.3048)
			(end 0.67945 0.3048)
			(stroke
				(width 0.1)
				(type default)
			)
			(layer "B.Fab")
		)
		(fp_line
			(start 0.67945 0.3048)
			(end 0.67945 -0.305054)
			(stroke
				(width 0.1)
				(type default)
			)
			(layer "B.Fab")
		)
		(fp_line
			(start -0.120396 0.2794)
			(end 0.12065 0.2794)
			(stroke
				(width 0.1)
				(type default)
			)
			(layer "B.Fab")
		)
		(fp_line
			(start 0.12065 0.2794)
			(end 0.12065 0.3048)
			(stroke
				(width 0.1)
				(type default)
			)
			(layer "B.Fab")
		)
		(fp_line
			(start -0.12065 -0.2794)
			(end -0.12065 -0.3048)
			(stroke
				(width 0.1)
				(type default)
			)
			(layer "B.Fab")
		)
		(fp_line
			(start 0.12065 -0.2794)
			(end -0.12065 -0.2794)
			(stroke
				(width 0.1)
				(type default)
			)
			(layer "B.Fab")
		)
		(fp_line
			(start -0.67945 -0.3048)
			(end -0.67945 0.3048)
			(stroke
				(width 0.1)
				(type default)
			)
			(layer "B.Fab")
		)
		(fp_line
			(start -0.12065 -0.3048)
			(end -0.67945 -0.3048)
			(stroke
				(width 0.1)
				(type default)
			)
			(layer "B.Fab")
		)
		(fp_line
			(start 0.12065 -0.305054)
			(end 0.12065 -0.2794)
			(stroke
				(width 0.1)
				(type default)
			)
			(layer "B.Fab")
		)
		(fp_line
			(start 0.67945 -0.305054)
			(end 0.12065 -0.305054)
			(stroke
				(width 0.1)
				(type default)
			)
			(layer "B.Fab")
		)
		(pad "1" smd circle
			(at 0.40005 0 90)
			(size 0 0)
			(layers "B.Cu" "B.Mask" "B.Paste")
			(net "P12V_AUX")
		)
		(pad "2" smd circle
			(at -0.40005 0 90)
			(size 0 0)
			(layers "B.Cu" "B.Mask" "B.Paste")
			(net "PWRGD_P5V_ISO_R")
		)
	)
	(footprint ""
		(layer "B.Cu")
		(at 178.9557 -114.17554 -90)
		(property "Reference" "C1919"
			(at 0 0 90)
			(layer "B.SilkS")
			(hide yes)
			(effects
				(font
					(size 1.27 1.27)
				)
				(justify mirror)
			)
		)
		(property "Value" ""
			(at 0 0 90)
			(layer "B.Fab")
			(effects
				(font
					(size 1.27 1.27)
				)
				(justify mirror)
			)
		)
		(duplicate_pad_numbers_are_jumpers no)
		(fp_line
			(start -0.69215 0.2921)
			(end 0.69215 0.2921)
			(stroke
				(width 0.1524)
				(type default)
			)
			(layer "B.SilkS")
		)
		(fp_line
			(start 0.69215 0.2921)
			(end 0.69215 -0.2921)
			(stroke
				(width 0.1524)
				(type default)
			)
			(layer "B.SilkS")
		)
		(fp_line
			(start -0.69215 -0.2921)
			(end -0.69215 0.2921)
			(stroke
				(width 0.1524)
				(type default)
			)
			(layer "B.SilkS")
		)
		(fp_line
			(start 0.69215 -0.2921)
			(end -0.69215 -0.2921)
			(stroke
				(width 0.1524)
				(type default)
			)
			(layer "B.SilkS")
		)
		(fp_line
			(start -0.51435 0.2794)
			(end 0.51435 0.2794)
			(stroke
				(width 0.1)
				(type default)
			)
			(layer "B.Fab")
		)
		(fp_line
			(start 0.51435 0.2794)
			(end 0.51435 -0.2794)
			(stroke
				(width 0.1)
				(type default)
			)
			(layer "B.Fab")
		)
		(fp_line
			(start -0.51435 -0.2794)
			(end -0.51435 0.2794)
			(stroke
				(width 0.1)
				(type default)
			)
			(layer "B.Fab")
		)
		(fp_line
			(start 0.51435 -0.2794)
			(end -0.51435 -0.2794)
			(stroke
				(width 0.1)
				(type default)
			)
			(layer "B.Fab")
		)
		(pad "1" smd circle
			(at 0.40005 0 90)
			(size 0 0)
			(layers "B.Cu" "B.Mask" "B.Paste")
			(net "VCC_PLD_CORE")
		)
		(pad "2" smd circle
			(at -0.40005 0 90)
			(size 0 0)
			(layers "B.Cu" "B.Mask" "B.Paste")
			(net "GND")
		)
		(zone
			(layer "B.Cu")
			(hatch none 0.5)
			(connect_pads
				(clearance 0)
			)
			(min_thickness 0.25)
			(keepout
				(tracks not_allowed)
				(vias allowed)
				(pads allowed)
				(copperpour not_allowed)
				(footprints allowed)
			)
			(placement
				(enabled no)
				(sheetname "")
			)
			(fill
				(thermal_gap 0.5)
				(thermal_bridge_width 0.5)
				(island_removal_mode 0)
			)
			(polygon
				(pts
					(xy 178.86807 -113.98504) (xy 178.809904 -114.07648) (xy 178.809904 -114.27587) (xy 178.86807 -114.36604)
					(xy 179.04333 -114.36604) (xy 179.10175 -114.27587) (xy 179.10175 -114.07648) (xy 179.043584 -113.98504)
				)
			)
		)
	)
)
